(kicad_pcb
	(version 20241229)
	(generator "pcbnew")
	(generator_version "9.0")
	(general
		(thickness 1.294)
		(legacy_teardrops no)
	)
	(paper "A3")
	(title_block
		(title "Kintex 410T devboard")
		(date "2024-04-03")
		(rev "1.1.2")
		(comment 9 "footprints 367-372 of 975")
	)
	(layers
		(0 "F.Cu" mixed)
		(4 "In1.Cu" power)
		(6 "In2.Cu" power)
		(8 "In3.Cu" mixed)
		(10 "In4.Cu" power)
		(12 "In5.Cu" mixed)
		(14 "In6.Cu" power)
		(16 "In7.Cu" mixed)
		(18 "In8.Cu" power)
		(2 "B.Cu" mixed)
		(9 "F.Adhes" user "F.Adhesive")
		(11 "B.Adhes" user "B.Adhesive")
		(13 "F.Paste" user)
		(15 "B.Paste" user)
		(5 "F.SilkS" user "F.Silkscreen")
		(7 "B.SilkS" user "B.Silkscreen")
		(1 "F.Mask" user)
		(3 "B.Mask" user)
		(17 "Dwgs.User" user "User.Drawings")
		(19 "Cmts.User" user "User.Comments")
		(21 "Eco1.User" user "User.Eco1")
		(23 "Eco2.User" user "User.Eco2")
		(25 "Edge.Cuts" user)
		(27 "Margin" user)
		(31 "F.CrtYd" user "F.Courtyard")
		(29 "B.CrtYd" user "B.Courtyard")
		(35 "F.Fab" user)
		(33 "B.Fab" user)
	)
	(footprint "antmicro-footprints:C_0402_1005Metric"
		(layer "F.Cu")
		(at 168 176.1625 90)
		(descr "Capacitor SMD 0402")
		(tags "capacitor SMD 0402")
		(property "Reference" "C335"
			(at -1.4375 -0.45 90)
			(layer "F.SilkS")
			(effects
				(font
					(size 0.7 0.7)
					(thickness 0.15)
				)
				(justify left bottom)
			)
		)
		(property "Value" "C_1u_0402"
			(at 0 1.4 90)
			(layer "F.Fab")
			(effects
				(font
					(size 0.7 0.7)
					(thickness 0.15)
				)
				(justify left bottom)
			)
		)
		(property "Description" "SMD Multilayer Ceramic Capacitor, 1 µF, 10 V, 0402 [1005 Metric], ± 10%, X6S, C"
			(at 0 0 90)
			(layer "F.Fab")
			(hide yes)
			(effects
				(font
					(size 1.27 1.27)
					(thickness 0.15)
				)
			)
		)
		(property "Author" "Antmicro"
			(at 344.1625 8.1625 0)
			(layer "F.Fab")
			(hide yes)
			(effects
				(font
					(size 1 1)
					(thickness 0.15)
				)
			)
		)
		(property "DNP" "DNP"
			(at 344.1625 8.1625 0)
			(layer "F.Fab")
			(hide yes)
			(effects
				(font
					(size 1 1)
					(thickness 0.15)
				)
			)
		)
		(property "Dielectric" ""
			(at 344.1625 8.1625 0)
			(layer "F.Fab")
			(hide yes)
			(effects
				(font
					(size 1 1)
					(thickness 0.15)
				)
			)
		)
		(property "License" "Apache-2.0"
			(at 344.1625 8.1625 0)
			(layer "F.Fab")
			(hide yes)
			(effects
				(font
					(size 1 1)
					(thickness 0.15)
				)
			)
		)
		(property "MPN" "C1005X6S1A105K050BC"
			(at 344.1625 8.1625 0)
			(layer "F.Fab")
			(hide yes)
			(effects
				(font
					(size 1 1)
					(thickness 0.15)
				)
			)
		)
		(property "Manufacturer" "TDK"
			(at 344.1625 8.1625 0)
			(layer "F.Fab")
			(hide yes)
			(effects
				(font
					(size 1 1)
					(thickness 0.15)
				)
			)
		)
		(property "Val" "1u"
			(at 344.1625 8.1625 0)
			(layer "F.Fab")
			(hide yes)
			(effects
				(font
					(size 1 1)
					(thickness 0.15)
				)
			)
		)
		(property "Voltage" ""
			(at 344.1625 8.1625 0)
			(layer "F.Fab")
			(hide yes)
			(effects
				(font
					(size 1 1)
					(thickness 0.15)
				)
			)
		)
		(property "dnp" ""
			(at 344.1625 8.1625 0)
			(layer "F.Fab")
			(hide yes)
			(effects
				(font
					(size 1 1)
					(thickness 0.15)
				)
			)
		)
		(property "exclude_from_bom" ""
			(at 344.1625 8.1625 0)
			(layer "F.Fab")
			(hide yes)
			(effects
				(font
					(size 1 1)
					(thickness 0.15)
				)
			)
		)
		(sheetname "DC-DC Converters")
		(sheetfile "dc-dc.kicad_sch")
		(attr smd exclude_from_bom)
		(fp_rect
			(start -0.925 -0.47)
			(end 0.925 0.47)
			(stroke
				(width 0.05)
				(type default)
			)
			(fill no)
			(layer "F.CrtYd")
		)
		(fp_line
			(start 0.504 -0.25)
			(end 0.504 0.248)
			(stroke
				(width 0.15)
				(type solid)
			)
			(layer "F.Fab")
		)
		(fp_line
			(start -0.494 -0.25)
			(end 0.504 -0.25)
			(stroke
				(width 0.15)
				(type solid)
			)
			(layer "F.Fab")
		)
		(fp_line
			(start 0.504 0.248)
			(end -0.494 0.248)
			(stroke
				(width 0.15)
				(type solid)
			)
			(layer "F.Fab")
		)
		(fp_line
			(start -0.494 0.248)
			(end -0.494 -0.25)
			(stroke
				(width 0.15)
				(type solid)
			)
			(layer "F.Fab")
		)
		(pad "1" smd roundrect
			(at -0.48 0 90)
			(size 0.59 0.64)
			(layers "F.Cu" "F.Mask" "F.Paste")
			(roundrect_rratio 0.25)
			(net 1 "GND")
			(pintype "passive")
		)
		(pad "2" smd roundrect
			(at 0.48 0 90)
			(size 0.59 0.64)
			(layers "F.Cu" "F.Mask" "F.Paste")
			(roundrect_rratio 0.25)
			(net 25 "+1V35")
			(pintype "passive")
		)
	)
	(footprint "antmicro-footprints:R_0402_1005Metric"
		(layer "F.Cu")
		(at 155.8125 175.7 180)
		(descr "Resistor SMD 0402")
		(tags "resistor SMD 0402")
		(property "Reference" "R311"
			(at 0.6625 -4.7 270)
			(layer "F.SilkS")
			(effects
				(font
					(size 0.7 0.7)
					(thickness 0.15)
				)
				(justify left bottom)
			)
		)
		(property "Value" "R_0R_0402"
			(at 0 1.4 180)
			(layer "F.Fab")
			(effects
				(font
					(size 0.7 0.7)
					(thickness 0.15)
				)
				(justify left bottom)
			)
		)
		(property "Description" "SMD Chip Resistor, Jumper, 0 ohm, 100 mW, 0402 [1005 Metric], Thick Film, General Purpose"
			(at 0 0 180)
			(layer "F.Fab")
			(hide yes)
			(effects
				(font
					(size 1.27 1.27)
					(thickness 0.15)
				)
			)
		)
		(property "Author" "Antmicro"
			(at 311.625 351.4 0)
			(layer "F.Fab")
			(hide yes)
			(effects
				(font
					(size 1 1)
					(thickness 0.15)
				)
			)
		)
		(property "Current" "1A"
			(at 311.625 351.4 0)
			(layer "F.Fab")
			(hide yes)
			(effects
				(font
					(size 1 1)
					(thickness 0.15)
				)
			)
		)
		(property "License" "Apache-2.0"
			(at 311.625 351.4 0)
			(layer "F.Fab")
			(hide yes)
			(effects
				(font
					(size 1 1)
					(thickness 0.15)
				)
			)
		)
		(property "MPN" "ERJ2GE0R00X"
			(at 311.625 351.4 0)
			(layer "F.Fab")
			(hide yes)
			(effects
				(font
					(size 1 1)
					(thickness 0.15)
				)
			)
		)
		(property "Manufacturer" "Panasonic"
			(at 311.625 351.4 0)
			(layer "F.Fab")
			(hide yes)
			(effects
				(font
					(size 1 1)
					(thickness 0.15)
				)
			)
		)
		(property "Tolerance" ""
			(at 311.625 351.4 0)
			(layer "F.Fab")
			(hide yes)
			(effects
				(font
					(size 1 1)
					(thickness 0.15)
				)
			)
		)
		(property "Val" "0R"
			(at 311.625 351.4 0)
			(layer "F.Fab")
			(hide yes)
			(effects
				(font
					(size 1 1)
					(thickness 0.15)
				)
			)
		)
		(sheetname "DC-DC Converters")
		(sheetfile "dc-dc.kicad_sch")
		(attr smd)
		(fp_rect
			(start -0.925 -0.47)
			(end 0.925 0.47)
			(stroke
				(width 0.05)
				(type default)
			)
			(fill no)
			(layer "F.CrtYd")
		)
		(fp_rect
			(start -0.5 -0.25)
			(end 0.5 0.25)
			(stroke
				(width 0.15)
				(type solid)
			)
			(fill no)
			(layer "F.Fab")
		)
		(pad "1" smd roundrect
			(at -0.48 0 180)
			(size 0.59 0.64)
			(layers "F.Cu" "F.Mask" "F.Paste")
			(roundrect_rratio 0.25)
			(net 963 "/DC-DC Converters/FB4")
			(pintype "passive")
		)
		(pad "2" smd roundrect
			(at 0.48 0 180)
			(size 0.59 0.64)
			(layers "F.Cu" "F.Mask" "F.Paste")
			(roundrect_rratio 0.25)
			(net 738 "/DC-DC Converters/1V7_local")
			(pintype "passive")
		)
	)
	(footprint "antmicro-footprints:FB_0603_1608Metric"
		(layer "F.Cu")
		(at 220.603 154.66 180)
		(property "Reference" "FB8"
			(at 1.003 -1.44 180)
			(layer "F.SilkS")
			(effects
				(font
					(size 0.7 0.7)
					(thickness 0.15)
				)
				(justify left bottom)
			)
		)
		(property "Value" "FB_120Z_2A_Murata-BLM18PG_0603"
			(at 0 1.7 180)
			(layer "F.Fab")
			(effects
				(font
					(size 0.7 0.7)
					(thickness 0.15)
				)
				(justify left bottom)
			)
		)
		(property "Description" "Ferrite Bead, 0603 [1608 Metric], 120 ohm, 2 A, BLM18P, 0.05 ohm, ± 25%, DC power line"
			(at 0 0 180)
			(layer "F.Fab")
			(hide yes)
			(effects
				(font
					(size 1.27 1.27)
					(thickness 0.15)
				)
			)
		)
		(property "Author" "Antmicro"
			(at 441.206 309.32 0)
			(layer "F.Fab")
			(hide yes)
			(effects
				(font
					(size 1 1)
					(thickness 0.15)
				)
			)
		)
		(property "Current" ""
			(at 441.206 309.32 0)
			(layer "F.Fab")
			(hide yes)
			(effects
				(font
					(size 1 1)
					(thickness 0.15)
				)
			)
		)
		(property "License" "Apache-2.0"
			(at 441.206 309.32 0)
			(layer "F.Fab")
			(hide yes)
			(effects
				(font
					(size 1 1)
					(thickness 0.15)
				)
			)
		)
		(property "MPN" "BLM18PG121SN1D"
			(at 441.206 309.32 0)
			(layer "F.Fab")
			(hide yes)
			(effects
				(font
					(size 1 1)
					(thickness 0.15)
				)
			)
		)
		(property "Manufacturer" "Murata"
			(at 441.206 309.32 0)
			(layer "F.Fab")
			(hide yes)
			(effects
				(font
					(size 1 1)
					(thickness 0.15)
				)
			)
		)
		(property "Val" "120Z/2A"
			(at 441.206 309.32 0)
			(layer "F.Fab")
			(hide yes)
			(effects
				(font
					(size 1 1)
					(thickness 0.15)
				)
			)
		)
		(sheetname "HDMI + Ethernet")
		(sheetfile "hdmi-ethernet.kicad_sch")
		(attr smd)
		(fp_line
			(start -0.15 0.4)
			(end 0.15 0.4)
			(stroke
				(width 0.15)
				(type solid)
			)
			(layer "F.SilkS")
		)
		(fp_line
			(start -0.15 -0.4)
			(end 0.15 -0.4)
			(stroke
				(width 0.15)
				(type solid)
			)
			(layer "F.SilkS")
		)
		(fp_rect
			(start -1.25 -0.65)
			(end 1.25 0.65)
			(stroke
				(width 0.05)
				(type solid)
			)
			(fill no)
			(layer "F.CrtYd")
		)
		(fp_line
			(start 0.8 0.406)
			(end -0.803 0.406)
			(stroke
				(width 0.15)
				(type solid)
			)
			(layer "F.Fab")
		)
		(fp_line
			(start 0.8 -0.408)
			(end 0.8 0.406)
			(stroke
				(width 0.15)
				(type solid)
			)
			(layer "F.Fab")
		)
		(fp_line
			(start 0.8 -0.408)
			(end -0.803 -0.408)
			(stroke
				(width 0.15)
				(type solid)
			)
			(layer "F.Fab")
		)
		(fp_line
			(start -0.803 0.406)
			(end -0.803 -0.408)
			(stroke
				(width 0.15)
				(type solid)
			)
			(layer "F.Fab")
		)
		(pad "1" smd roundrect
			(at -0.7 0 180)
			(size 0.8 1)
			(layers "F.Cu" "F.Mask" "F.Paste")
			(roundrect_rratio 0.2)
			(net 721 "/HDMI + Ethernet/ETH_3V3")
			(pintype "passive")
		)
		(pad "2" smd roundrect
			(at 0.7 0 180)
			(size 0.8 1)
			(layers "F.Cu" "F.Mask" "F.Paste")
			(roundrect_rratio 0.2)
			(net 24 "+3V3")
			(pintype "passive")
		)
	)
	(footprint "antmicro-footprints:R_0402_1005Metric"
		(layer "F.Cu")
		(at 157.775 156.515 90)
		(descr "Resistor SMD 0402")
		(tags "resistor SMD 0402")
		(property "Reference" "R323"
			(at -3.685 0.425 90)
			(layer "F.SilkS")
			(effects
				(font
					(size 0.7 0.7)
					(thickness 0.15)
				)
				(justify left bottom)
			)
		)
		(property "Value" "R_10k_0402"
			(at 0 1.4 90)
			(layer "F.Fab")
			(effects
				(font
					(size 0.7 0.7)
					(thickness 0.15)
				)
				(justify left bottom)
			)
		)
		(property "Description" "SMD Chip Resistor, 10 kohm, ± 1%, 62.5 mW, 0402 [1005 Metric], Thick Film, General Purpose"
			(at 0 0 90)
			(layer "F.Fab")
			(hide yes)
			(effects
				(font
					(size 1.27 1.27)
					(thickness 0.15)
				)
			)
		)
		(property "Author" "Antmicro"
			(at 314.29 -1.26 0)
			(layer "F.Fab")
			(hide yes)
			(effects
				(font
					(size 1 1)
					(thickness 0.15)
				)
			)
		)
		(property "License" "Apache-2.0"
			(at 314.29 -1.26 0)
			(layer "F.Fab")
			(hide yes)
			(effects
				(font
					(size 1 1)
					(thickness 0.15)
				)
			)
		)
		(property "MPN" "CR0402-FX-1002GLF"
			(at 314.29 -1.26 0)
			(layer "F.Fab")
			(hide yes)
			(effects
				(font
					(size 1 1)
					(thickness 0.15)
				)
			)
		)
		(property "Manufacturer" "Bourns"
			(at 314.29 -1.26 0)
			(layer "F.Fab")
			(hide yes)
			(effects
				(font
					(size 1 1)
					(thickness 0.15)
				)
			)
		)
		(property "Tolerance" "1%"
			(at 314.29 -1.26 0)
			(layer "F.Fab")
			(hide yes)
			(effects
				(font
					(size 1 1)
					(thickness 0.15)
				)
			)
		)
		(property "Val" "10k"
			(at 314.29 -1.26 0)
			(layer "F.Fab")
			(hide yes)
			(effects
				(font
					(size 1 1)
					(thickness 0.15)
				)
			)
		)
		(sheetname "DC-DC Converters")
		(sheetfile "dc-dc.kicad_sch")
		(attr smd)
		(fp_rect
			(start -0.925 -0.47)
			(end 0.925 0.47)
			(stroke
				(width 0.05)
				(type default)
			)
			(fill no)
			(layer "F.CrtYd")
		)
		(fp_rect
			(start -0.5 -0.25)
			(end 0.5 0.25)
			(stroke
				(width 0.15)
				(type solid)
			)
			(fill no)
			(layer "F.Fab")
		)
		(pad "1" smd roundrect
			(at -0.48 0 90)
			(size 0.59 0.64)
			(layers "F.Cu" "F.Mask" "F.Paste")
			(roundrect_rratio 0.25)
			(net 744 "/DC-DC Converters/VDDR_VRI")
			(pintype "passive")
		)
		(pad "2" smd roundrect
			(at 0.48 0 90)
			(size 0.59 0.64)
			(layers "F.Cu" "F.Mask" "F.Paste")
			(roundrect_rratio 0.25)
			(net 25 "+1V35")
			(pintype "passive")
		)
	)
	(footprint "antmicro-footprints:R_0402_1005Metric"
		(layer "F.Cu")
		(at 156.225 157)
		(descr "Resistor SMD 0402")
		(tags "resistor SMD 0402")
		(property "Reference" "R324"
			(at -1.875 2.35 0)
			(layer "F.SilkS")
			(effects
				(font
					(size 0.7 0.7)
					(thickness 0.15)
				)
				(justify left bottom)
			)
		)
		(property "Value" "R_10k_0402"
			(at 0 1.4 0)
			(layer "F.Fab")
			(effects
				(font
					(size 0.7 0.7)
					(thickness 0.15)
				)
				(justify left bottom)
			)
		)
		(property "Description" "SMD Chip Resistor, 10 kohm, ± 1%, 62.5 mW, 0402 [1005 Metric], Thick Film, General Purpose"
			(at 0 0 0)
			(layer "F.Fab")
			(hide yes)
			(effects
				(font
					(size 1.27 1.27)
					(thickness 0.15)
				)
			)
		)
		(property "Author" "Antmicro"
			(at 0 0 0)
			(layer "F.Fab")
			(hide yes)
			(effects
				(font
					(size 1 1)
					(thickness 0.15)
				)
			)
		)
		(property "License" "Apache-2.0"
			(at 0 0 0)
			(layer "F.Fab")
			(hide yes)
			(effects
				(font
					(size 1 1)
					(thickness 0.15)
				)
			)
		)
		(property "MPN" "CR0402-FX-1002GLF"
			(at 0 0 0)
			(layer "F.Fab")
			(hide yes)
			(effects
				(font
					(size 1 1)
					(thickness 0.15)
				)
			)
		)
		(property "Manufacturer" "Bourns"
			(at 0 0 0)
			(layer "F.Fab")
			(hide yes)
			(effects
				(font
					(size 1 1)
					(thickness 0.15)
				)
			)
		)
		(property "Tolerance" "1%"
			(at 0 0 0)
			(layer "F.Fab")
			(hide yes)
			(effects
				(font
					(size 1 1)
					(thickness 0.15)
				)
			)
		)
		(property "Val" "10k"
			(at 0 0 0)
			(layer "F.Fab")
			(hide yes)
			(effects
				(font
					(size 1 1)
					(thickness 0.15)
				)
			)
		)
		(sheetname "DC-DC Converters")
		(sheetfile "dc-dc.kicad_sch")
		(attr smd)
		(fp_rect
			(start -0.925 -0.47)
			(end 0.925 0.47)
			(stroke
				(width 0.05)
				(type default)
			)
			(fill no)
			(layer "F.CrtYd")
		)
		(fp_rect
			(start -0.5 -0.25)
			(end 0.5 0.25)
			(stroke
				(width 0.15)
				(type solid)
			)
			(fill no)
			(layer "F.Fab")
		)
		(pad "1" smd roundrect
			(at -0.48 0)
			(size 0.59 0.64)
			(layers "F.Cu" "F.Mask" "F.Paste")
			(roundrect_rratio 0.25)
			(net 1 "GND")
			(pintype "passive")
		)
		(pad "2" smd roundrect
			(at 0.48 0)
			(size 0.59 0.64)
			(layers "F.Cu" "F.Mask" "F.Paste")
			(roundrect_rratio 0.25)
			(net 744 "/DC-DC Converters/VDDR_VRI")
			(pintype "passive")
		)
	)
	(footprint "antmicro-footprints:R_0402_1005Metric"
		(layer "F.Cu")
		(at 236.2 130.55 180)
		(descr "Resistor SMD 0402")
		(tags "resistor SMD 0402")
		(property "Reference" "R178"
			(at 1.825 3.525 180)
			(layer "F.SilkS")
			(effects
				(font
					(size 0.7 0.7)
					(thickness 0.15)
				)
				(justify left bottom)
			)
		)
		(property "Value" "R_33R_0402"
			(at 0 1.4 180)
			(layer "F.Fab")
			(effects
				(font
					(size 0.7 0.7)
					(thickness 0.15)
				)
				(justify left bottom)
			)
		)
		(property "Description" "SMD Chip Resistor, 33 ohm, ± 1%, 62.5 mW, 0402 [1005 Metric], Thick Film, General Purpose"
			(at 0 0 180)
			(layer "F.Fab")
			(hide yes)
			(effects
				(font
					(size 1.27 1.27)
					(thickness 0.15)
				)
			)
		)
		(property "Author" "Antmicro"
			(at 472.4 261.1 0)
			(layer "F.Fab")
			(hide yes)
			(effects
				(font
					(size 1 1)
					(thickness 0.15)
				)
			)
		)
		(property "License" "Apache-2.0"
			(at 472.4 261.1 0)
			(layer "F.Fab")
			(hide yes)
			(effects
				(font
					(size 1 1)
					(thickness 0.15)
				)
			)
		)
		(property "MPN" "CR0402-FX-33R0GLF"
			(at 472.4 261.1 0)
			(layer "F.Fab")
			(hide yes)
			(effects
				(font
					(size 1 1)
					(thickness 0.15)
				)
			)
		)
		(property "Manufacturer" "Bourns"
			(at 472.4 261.1 0)
			(layer "F.Fab")
			(hide yes)
			(effects
				(font
					(size 1 1)
					(thickness 0.15)
				)
			)
		)
		(property "Tolerance" "1%"
			(at 472.4 261.1 0)
			(layer "F.Fab")
			(hide yes)
			(effects
				(font
					(size 1 1)
					(thickness 0.15)
				)
			)
		)
		(property "Val" "33R"
			(at 472.4 261.1 0)
			(layer "F.Fab")
			(hide yes)
			(effects
				(font
					(size 1 1)
					(thickness 0.15)
				)
			)
		)
		(sheetname "USB PHY")
		(sheetfile "usb-phy.kicad_sch")
		(attr smd)
		(fp_rect
			(start -0.925 -0.47)
			(end 0.925 0.47)
			(stroke
				(width 0.05)
				(type default)
			)
			(fill no)
			(layer "F.CrtYd")
		)
		(fp_rect
			(start -0.5 -0.25)
			(end 0.5 0.25)
			(stroke
				(width 0.15)
				(type solid)
			)
			(fill no)
			(layer "F.Fab")
		)
		(pad "1" smd roundrect
			(at -0.48 0 180)
			(size 0.59 0.64)
			(layers "F.Cu" "F.Mask" "F.Paste")
			(roundrect_rratio 0.25)
			(net 370 "Net-(U22-B3Y)")
			(pintype "passive")
		)
		(pad "2" smd roundrect
			(at 0.48 0 180)
			(size 0.59 0.64)
			(layers "F.Cu" "F.Mask" "F.Paste")
			(roundrect_rratio 0.25)
			(net 220 "/FPGA Config/JTAG.TDI")
			(pintype "passive")
		)
	)
)
